FILE_TYPE = MULTI_PHYS_TABLE;

PART 'BSS138DW7F'

{========================================================================================}
:VALUE          | PART_TYPE | MATERIAL | PART_NUMBER      = STANDARD         | LIFECYCLE        | PART_NUMBER   | JEDEC_TYPE | DESCRIPTION                            | MANUFTR | MANUF_PN       | RD_CMPLS_LVL | CMPLS_LVL | CLASS | DIP_SMD | FROM_PJ    | DATA               | FP_ECN | EE_CHECK_LIST | STATUS | PREFERENCE | NOT_INSERT ;
{========================================================================================}
 'BSS138DW-7-F' | 'SMLF'    | 'IC'     | 'BAM01380032'(!) = ''               | ''               | 'BAM01380032' |'SOT363A'| 'TRANS MOSFET BSS138DW-7-F(50V,200MA)' | 'DDS'   | 'BSS138DW-7-F' | 'EP(V1)'     | ''        | 'IC'  | ''      | 'S2N-JUMP' | 'BSS138DW-7-F.pdf' | ''     | ''            | ''     | ''         | ''        
 'BSS138DW-7-F' | 'SMLF'    | 'EMPTY'  | 'BAM01380032'(!) = ''               | ''               | 'BAM01380032' |'SOT363A'| 'TRANS MOSFET BSS138DW-7-F(50V,200MA)' | 'DDS'   | 'BSS138DW-7-F' | 'EP(V1)'     | ''        | 'IC'  | ''      | 'S2N-JUMP' | 'BSS138DW-7-F.pdf' | ''     | ''            | ''     | ''         | ''        

END_PART

END.

